# BASEBOARD_FAB2 (Tioga Pass) — schematic netlist excerpt (pin names and nets, part order shuffled) for the footprints in the layout excerpt that follows; sources: Cadence DE-HDL packaged netlist, KiCad conversion of Wiwynn_Tioga_Pass_MB.brd

R1L43  RES  330 5% CHIP  pkg 0402  page 158 : A = FM_UARTSW_LSB_R_N ; B = P3V3_STBY
C9N6  CAP  0.22UF 16V 10% X7R  pkg 0402  page 182 : A = P3E_CPU1_PE3_MP_C_TXN<13> ; B = P3E_CPU1_PE3_MP_TXN<13>
C25W91  CAP_A  1.0UF 6.3V 10% X6S  pkg 0402V  page 254 : A = P3V3_STBY ; B = GND

(kicad_pcb
	(version 20260206)
	(generator "pcbnew")
	(generator_version "10.0")
	(general
		(thickness 1.6)
		(legacy_teardrops no)
	)
	(paper "A4")
	(title_block
		(title "Wiwynn_Tioga_Pass_MB.brd")
		(comment 1 "Tioga Pass / footprints 2628-2630 of 4770")
	)
	(layers
		(0 "F.Cu" signal "TOP")
		(4 "In1.Cu" signal "L2GND")
		(6 "In2.Cu" signal "L3")
		(8 "In3.Cu" signal "L4GND")
		(10 "In4.Cu" signal "L5")
		(12 "In5.Cu" signal "L6GND")
		(14 "In6.Cu" signal "L7VCC")
		(16 "In7.Cu" signal "L8VCC")
		(18 "In8.Cu" signal "L9GND")
		(20 "In9.Cu" signal "L10")
		(22 "In10.Cu" signal "L11GND")
		(24 "In11.Cu" signal "L12")
		(26 "In12.Cu" signal "L13GND")
		(2 "B.Cu" signal "BOTTOM")
		(9 "F.Adhes" user "F.Adhesive")
		(11 "B.Adhes" user "B.Adhesive")
		(13 "F.Paste" user "Package Geometry/Pastemask Top")
		(15 "B.Paste" user "Package Geometry/Pastemask Bottom")
		(5 "F.SilkS" user "Ref Des/Silkscreen Top")
		(7 "B.SilkS" user "Ref Des/Silkscreen Bottom")
		(1 "F.Mask" user "Board Geometry/Soldermask Top")
		(3 "B.Mask" user "Board Geometry/Soldermask Bottom")
		(17 "Dwgs.User" user "User.Drawings")
		(19 "Cmts.User" user "User.Comments")
		(21 "Eco1.User" user "User.Eco1")
		(23 "Eco2.User" user "User.Eco2")
		(25 "Edge.Cuts" user "Board Geometry/Outline")
		(27 "Margin" user)
		(31 "F.CrtYd" user "Package Geometry/Place Bound Top")
		(29 "B.CrtYd" user "Package Geometry/Place Bound Bottom")
		(35 "F.Fab" user "Ref Des/Assembly Top")
		(33 "B.Fab" user "Ref Des/Assembly Bottom")
	)
	(footprint ""
		(layer "B.Cu")
		(at 17.83842 -105.20172 90)
		(property "Reference" "C9N6"
			(at 0 0 90)
			(layer "B.SilkS")
			(hide yes)
			(effects
				(font
					(size 1.27 1.27)
				)
				(justify mirror)
			)
		)
		(property "Value" ""
			(at 0 0 90)
			(layer "B.Fab")
			(effects
				(font
					(size 1.27 1.27)
				)
				(justify mirror)
			)
		)
		(duplicate_pad_numbers_are_jumpers no)
		(fp_poly
			(pts
				(xy -0.3048 -0.1016) (xy -0.3048 0.9906) (xy 0.3048 0.9906) (xy 0.3048 -0.1016)
			)
			(stroke
				(width 0)
				(type default)
			)
			(fill no)
			(layer "B.CrtYd")
		)
		(fp_line
			(start 0.3048 -0.1016)
			(end 0.3048 0.9906)
			(stroke
				(width 0.1)
				(type default)
			)
			(layer "B.Fab")
		)
		(fp_line
			(start -0.3048 -0.1016)
			(end 0.3048 -0.1016)
			(stroke
				(width 0.1)
				(type default)
			)
			(layer "B.Fab")
		)
		(fp_line
			(start 0.3048 0.9906)
			(end -0.3048 0.9906)
			(stroke
				(width 0.1)
				(type default)
			)
			(layer "B.Fab")
		)
		(fp_line
			(start -0.3048 0.9906)
			(end -0.3048 -0.1016)
			(stroke
				(width 0.1)
				(type default)
			)
			(layer "B.Fab")
		)
		(pad "1" smd rect
			(at 0 0 270)
			(size 0.508 0.508)
			(layers "B.Cu" "B.Mask" "B.Paste")
			(net "P3E_CPU1_PE3_MP_C_TXN<13>")
		)
		(pad "2" smd rect
			(at 0 0.889 270)
			(size 0.508 0.508)
			(layers "B.Cu" "B.Mask" "B.Paste")
			(net "P3E_CPU1_PE3_MP_TXN<13>")
		)
		(zone
			(layer "B.Cu")
			(hatch none 0.5)
			(connect_pads
				(clearance 0)
			)
			(min_thickness 0.25)
			(keepout
				(tracks allowed)
				(vias not_allowed)
				(pads allowed)
				(copperpour not_allowed)
				(footprints allowed)
			)
			(placement
				(enabled no)
				(sheetname "")
			)
			(fill
				(thermal_gap 0.5)
				(thermal_bridge_width 0.5)
				(island_removal_mode 0)
			)
			(polygon
				(pts
					(xy 18.09242 -105.45572) (xy 18.09242 -104.94772) (xy 18.47342 -104.94772) (xy 18.47342 -105.45572)
				)
			)
		)
		(zone
			(layer "B.Cu")
			(hatch none 0.5)
			(connect_pads
				(clearance 0)
			)
			(min_thickness 0.25)
			(keepout
				(tracks not_allowed)
				(vias allowed)
				(pads allowed)
				(copperpour not_allowed)
				(footprints allowed)
			)
			(placement
				(enabled no)
				(sheetname "")
			)
			(fill
				(thermal_gap 0.5)
				(thermal_bridge_width 0.5)
				(island_removal_mode 0)
			)
			(polygon
				(pts
					(xy 18.47342 -105.45572) (xy 18.47342 -104.94772) (xy 18.09242 -104.94772) (xy 18.09242 -105.45572)
				)
			)
		)
	)
	(footprint ""
		(layer "B.Cu")
		(at 498.602 -138.557 90)
		(property "Reference" "R1L43"
			(at 0 0 90)
			(layer "B.SilkS")
			(hide yes)
			(effects
				(font
					(size 1.27 1.27)
				)
				(justify mirror)
			)
		)
		(property "Value" ""
			(at 0 0 90)
			(layer "B.Fab")
			(effects
				(font
					(size 1.27 1.27)
				)
				(justify mirror)
			)
		)
		(duplicate_pad_numbers_are_jumpers no)
		(fp_poly
			(pts
				(xy 0.2794 -0.1016) (xy -0.2794 -0.1016) (xy -0.2794 0.9906) (xy 0.2794 0.9906)
			)
			(stroke
				(width 0)
				(type default)
			)
			(fill no)
			(layer "B.CrtYd")
		)
		(fp_line
			(start 0.2794 -0.1016)
			(end 0.2794 0.9906)
			(stroke
				(width 0.1)
				(type default)
			)
			(layer "B.Fab")
		)
		(fp_line
			(start -0.2794 -0.1016)
			(end 0.2794 -0.1016)
			(stroke
				(width 0.1)
				(type default)
			)
			(layer "B.Fab")
		)
		(fp_line
			(start 0.2794 0.9906)
			(end -0.2794 0.9906)
			(stroke
				(width 0.1)
				(type default)
			)
			(layer "B.Fab")
		)
		(fp_line
			(start -0.2794 0.9906)
			(end -0.2794 -0.1016)
			(stroke
				(width 0.1)
				(type default)
			)
			(layer "B.Fab")
		)
		(pad "1" smd rect
			(at 0 0 270)
			(size 0.508 0.508)
			(layers "B.Cu" "B.Mask" "B.Paste")
			(net "FM_UARTSW_LSB_R_N")
		)
		(pad "2" smd rect
			(at 0 0.889 270)
			(size 0.508 0.508)
			(layers "B.Cu" "B.Mask" "B.Paste")
			(net "P3V3_STBY")
		)
		(zone
			(layer "B.Cu")
			(hatch none 0.5)
			(connect_pads
				(clearance 0)
			)
			(min_thickness 0.25)
			(keepout
				(tracks allowed)
				(vias not_allowed)
				(pads allowed)
				(copperpour not_allowed)
				(footprints allowed)
			)
			(placement
				(enabled no)
				(sheetname "")
			)
			(fill
				(thermal_gap 0.5)
				(thermal_bridge_width 0.5)
				(island_removal_mode 0)
			)
			(polygon
				(pts
					(xy 498.856 -138.811) (xy 498.856 -138.303) (xy 499.237 -138.303) (xy 499.237 -138.811)
				)
			)
		)
		(zone
			(layer "B.Cu")
			(hatch none 0.5)
			(connect_pads
				(clearance 0)
			)
			(min_thickness 0.25)
			(keepout
				(tracks not_allowed)
				(vias allowed)
				(pads allowed)
				(copperpour not_allowed)
				(footprints allowed)
			)
			(placement
				(enabled no)
				(sheetname "")
			)
			(fill
				(thermal_gap 0.5)
				(thermal_bridge_width 0.5)
				(island_removal_mode 0)
			)
			(polygon
				(pts
					(xy 499.237 -138.811) (xy 499.237 -138.303) (xy 498.856 -138.303) (xy 498.856 -138.811)
				)
			)
		)
	)
	(footprint ""
		(layer "B.Cu")
		(at 442.3918 -141.062202 90)
		(property "Reference" "C25W91"
			(at 0.8382 -0.67818 90)
			(unlocked yes)
			(layer "B.SilkS")
			(effects
				(font
					(size 0.4064 0.254)
					(thickness 0.1524)
				)
				(justify left mirror)
			)
		)
		(property "Value" ""
			(at 0 0 90)
			(layer "B.Fab")
			(effects
				(font
					(size 1.27 1.27)
				)
				(justify mirror)
			)
		)
		(duplicate_pad_numbers_are_jumpers no)
		(fp_poly
			(pts
				(xy -0.3048 -0.1016) (xy -0.3048 0.9906) (xy 0.3048 0.9906) (xy 0.3048 -0.1016)
			)
			(stroke
				(width 0)
				(type default)
			)
			(fill no)
			(layer "B.CrtYd")
		)
		(fp_line
			(start 0.3048 -0.1016)
			(end 0.3048 0.9906)
			(stroke
				(width 0.1)
				(type default)
			)
			(layer "B.Fab")
		)
		(fp_line
			(start -0.3048 -0.1016)
			(end 0.3048 -0.1016)
			(stroke
				(width 0.1)
				(type default)
			)
			(layer "B.Fab")
		)
		(fp_line
			(start 0.3048 0.9906)
			(end -0.3048 0.9906)
			(stroke
				(width 0.1)
				(type default)
			)
			(layer "B.Fab")
		)
		(fp_line
			(start -0.3048 0.9906)
			(end -0.3048 -0.1016)
			(stroke
				(width 0.1)
				(type default)
			)
			(layer "B.Fab")
		)
		(pad "1" smd rect
			(at 0 0 270)
			(size 0.508 0.508)
			(layers "B.Cu" "B.Mask" "B.Paste")
			(net "P3V3_STBY")
		)
		(pad "2" smd rect
			(at 0 0.889 270)
			(size 0.508 0.508)
			(layers "B.Cu" "B.Mask" "B.Paste")
			(net "GND")
		)
		(zone
			(layer "B.Cu")
			(hatch none 0.5)
			(connect_pads
				(clearance 0)
			)
			(min_thickness 0.25)
			(keepout
				(tracks allowed)
				(vias not_allowed)
				(pads allowed)
				(copperpour not_allowed)
				(footprints allowed)
			)
			(placement
				(enabled no)
				(sheetname "")
			)
			(fill
				(thermal_gap 0.5)
				(thermal_bridge_width 0.5)
				(island_removal_mode 0)
			)
			(polygon
				(pts
					(xy 442.6458 -141.316202) (xy 442.6458 -140.808202) (xy 443.0268 -140.808202) (xy 443.0268 -141.316202)
				)
			)
		)
		(zone
			(layer "B.Cu")
			(hatch none 0.5)
			(connect_pads
				(clearance 0)
			)
			(min_thickness 0.25)
			(keepout
				(tracks not_allowed)
				(vias allowed)
				(pads allowed)
				(copperpour not_allowed)
				(footprints allowed)
			)
			(placement
				(enabled no)
				(sheetname "")
			)
			(fill
				(thermal_gap 0.5)
				(thermal_bridge_width 0.5)
				(island_removal_mode 0)
			)
			(polygon
				(pts
					(xy 443.0268 -141.316202) (xy 443.0268 -140.808202) (xy 442.6458 -140.808202) (xy 442.6458 -141.316202)
				)
			)
		)
	)
)
